#ISCELL
  mstr_misc dns *
  *
#ISCELL
  mstr_symbols bom_note *
  *
#ISCELL
  mstr_symbols cad_note *
  *
#ISCELL
  mstr_symbols intel_corp_bpage *
  *
#ISCELL
  mstr_standard offpage *
  page246_i1
#CELL
  mstr_discrete res *
  page246_i11
#CELL
  mstr_discrete res *
  page246_i12
#ISCELL
  mstr_symbols gnd *
  page246_i13
#ISCELL
  mstr_symbols gnd *
  page246_i14
#CELL
  mstr_memory w25q256 *
  page246_i17
#ISCELL
  mstr_standard offpage *
  page246_i18
#CELL
  w_hdl 82kr2f-1-gp *
  page246_i19
#ISCELL
  mstr_standard offpage *
  page246_i2
#CELL
  mstr_discrete res *
  page246_i20
#CELL
  dev_discrete cap_a *
  page246_i21
#CELL
  dev_discrete cap_a *
  page246_i22
#ISCELL
  mstr_standard offpage *
  page246_i3
#ISCELL
  mstr_standard offpage *
  page246_i4
#ISCELL
  mstr_symbols p3v3_stby *
  page246_i6
#ISCELL
  mstr_symbols gnd *
  page246_i7
#CELL
  mstr_discrete res *
  page246_i9
